(kicad_pcb
	(version 20260206)
	(generator "pcbnew")
	(generator_version "10.0")
	(general
		(thickness 1.6)
		(legacy_teardrops no)
	)
	(paper "A4")
	(title_block
		(title "12092022_DA0F0TMDCD0_F0T_Management_Board_D_brd_V3_OCP.brd")
		(comment 1 "Grand Teton / footprints 1410-1415 of 1440")
	)
	(layers
		(0 "F.Cu" signal "TOP")
		(4 "In1.Cu" signal "GND")
		(6 "In2.Cu" signal "IN1")
		(8 "In3.Cu" signal "GND1")
		(10 "In4.Cu" signal "IN2")
		(12 "In5.Cu" signal "VCC")
		(14 "In6.Cu" signal "VCC1")
		(16 "In7.Cu" signal "IN3")
		(18 "In8.Cu" signal "GND2")
		(20 "In9.Cu" signal "IN4")
		(22 "In10.Cu" signal "GND3")
		(2 "B.Cu" signal "BOTTOM")
		(9 "F.Adhes" user "F.Adhesive")
		(11 "B.Adhes" user "B.Adhesive")
		(13 "F.Paste" user "Package Geometry/Pastemask Top")
		(15 "B.Paste" user "Package Geometry/Pastemask Bottom")
		(5 "F.SilkS" user "Ref Des/Silkscreen Top")
		(7 "B.SilkS" user "Ref Des/Silkscreen Bottom")
		(1 "F.Mask" user "Board Geometry/Soldermask Top")
		(3 "B.Mask" user "Board Geometry/Soldermask Bottom")
		(17 "Dwgs.User" user "User.Drawings")
		(19 "Cmts.User" user "User.Comments")
		(21 "Eco1.User" user "User.Eco1")
		(23 "Eco2.User" user "User.Eco2")
		(25 "Edge.Cuts" user "Board Geometry/Outline")
		(27 "Margin" user)
		(31 "F.CrtYd" user "Package Geometry/Place Bound Top")
		(29 "B.CrtYd" user "Package Geometry/Place Bound Bottom")
		(35 "F.Fab" user "Ref Des/Assembly Top")
		(33 "B.Fab" user "Ref Des/Assembly Bottom")
	)
	(footprint ""
		(layer "B.Cu")
		(at 66.802 -12.446 180)
		(property "Reference" "R885"
			(at 0 0 0)
			(layer "B.SilkS")
			(hide yes)
			(effects
				(font
					(size 1.27 1.27)
				)
				(justify mirror)
			)
		)
		(property "Value" ""
			(at 0 0 0)
			(layer "B.Fab")
			(effects
				(font
					(size 1.27 1.27)
				)
				(justify mirror)
			)
		)
		(duplicate_pad_numbers_are_jumpers no)
		(fp_line
			(start 0.7874 0.4064)
			(end 0.7874 -0.4064)
			(stroke
				(width 0.1524)
				(type default)
			)
			(layer "B.SilkS")
		)
		(fp_line
			(start 0.7874 -0.4064)
			(end -0.7874 -0.4064)
			(stroke
				(width 0.1524)
				(type default)
			)
			(layer "B.SilkS")
		)
		(fp_line
			(start -0.7874 0.4064)
			(end 0.7874 0.4064)
			(stroke
				(width 0.1524)
				(type default)
			)
			(layer "B.SilkS")
		)
		(fp_line
			(start -0.7874 -0.4064)
			(end -0.7874 0.4064)
			(stroke
				(width 0.1524)
				(type default)
			)
			(layer "B.SilkS")
		)
		(fp_line
			(start 0.67945 0.3048)
			(end 0.67945 -0.305054)
			(stroke
				(width 0.1)
				(type default)
			)
			(layer "B.Fab")
		)
		(fp_line
			(start 0.67945 -0.305054)
			(end 0.12065 -0.305054)
			(stroke
				(width 0.1)
				(type default)
			)
			(layer "B.Fab")
		)
		(fp_line
			(start 0.12065 0.3048)
			(end 0.67945 0.3048)
			(stroke
				(width 0.1)
				(type default)
			)
			(layer "B.Fab")
		)
		(fp_line
			(start 0.12065 0.2794)
			(end 0.12065 0.3048)
			(stroke
				(width 0.1)
				(type default)
			)
			(layer "B.Fab")
		)
		(fp_line
			(start 0.12065 -0.2794)
			(end -0.12065 -0.2794)
			(stroke
				(width 0.1)
				(type default)
			)
			(layer "B.Fab")
		)
		(fp_line
			(start 0.12065 -0.305054)
			(end 0.12065 -0.2794)
			(stroke
				(width 0.1)
				(type default)
			)
			(layer "B.Fab")
		)
		(fp_line
			(start -0.120396 0.3048)
			(end -0.120396 0.2794)
			(stroke
				(width 0.1)
				(type default)
			)
			(layer "B.Fab")
		)
		(fp_line
			(start -0.120396 0.2794)
			(end 0.12065 0.2794)
			(stroke
				(width 0.1)
				(type default)
			)
			(layer "B.Fab")
		)
		(fp_line
			(start -0.12065 -0.2794)
			(end -0.12065 -0.3048)
			(stroke
				(width 0.1)
				(type default)
			)
			(layer "B.Fab")
		)
		(fp_line
			(start -0.12065 -0.3048)
			(end -0.67945 -0.3048)
			(stroke
				(width 0.1)
				(type default)
			)
			(layer "B.Fab")
		)
		(fp_line
			(start -0.67945 0.3048)
			(end -0.120396 0.3048)
			(stroke
				(width 0.1)
				(type default)
			)
			(layer "B.Fab")
		)
		(fp_line
			(start -0.67945 -0.3048)
			(end -0.67945 0.3048)
			(stroke
				(width 0.1)
				(type default)
			)
			(layer "B.Fab")
		)
		(pad "1" smd circle
			(at 0.40005 0)
			(size 0 0)
			(layers "B.Cu" "B.Mask" "B.Paste")
			(net "P1V8_AUX")
		)
		(pad "2" smd circle
			(at -0.40005 0)
			(size 0 0)
			(layers "B.Cu" "B.Mask" "B.Paste")
			(net "AC_PWR_BMC_BTN_N")
		)
	)
	(footprint ""
		(layer "B.Cu")
		(at 59.7916 -95.0214 180)
		(property "Reference" "R743"
			(at 0 0 0)
			(layer "B.SilkS")
			(hide yes)
			(effects
				(font
					(size 1.27 1.27)
				)
				(justify mirror)
			)
		)
		(property "Value" ""
			(at 0 0 0)
			(layer "B.Fab")
			(effects
				(font
					(size 1.27 1.27)
				)
				(justify mirror)
			)
		)
		(duplicate_pad_numbers_are_jumpers no)
		(fp_line
			(start 0.7874 0.4064)
			(end 0.7874 -0.4064)
			(stroke
				(width 0.1524)
				(type default)
			)
			(layer "B.SilkS")
		)
		(fp_line
			(start 0.7874 -0.4064)
			(end -0.7874 -0.4064)
			(stroke
				(width 0.1524)
				(type default)
			)
			(layer "B.SilkS")
		)
		(fp_line
			(start -0.7874 0.4064)
			(end 0.7874 0.4064)
			(stroke
				(width 0.1524)
				(type default)
			)
			(layer "B.SilkS")
		)
		(fp_line
			(start -0.7874 -0.4064)
			(end -0.7874 0.4064)
			(stroke
				(width 0.1524)
				(type default)
			)
			(layer "B.SilkS")
		)
		(fp_line
			(start 0.67945 0.3048)
			(end 0.67945 -0.305054)
			(stroke
				(width 0.1)
				(type default)
			)
			(layer "B.Fab")
		)
		(fp_line
			(start 0.67945 -0.305054)
			(end 0.12065 -0.305054)
			(stroke
				(width 0.1)
				(type default)
			)
			(layer "B.Fab")
		)
		(fp_line
			(start 0.12065 0.3048)
			(end 0.67945 0.3048)
			(stroke
				(width 0.1)
				(type default)
			)
			(layer "B.Fab")
		)
		(fp_line
			(start 0.12065 0.2794)
			(end 0.12065 0.3048)
			(stroke
				(width 0.1)
				(type default)
			)
			(layer "B.Fab")
		)
		(fp_line
			(start 0.12065 -0.2794)
			(end -0.12065 -0.2794)
			(stroke
				(width 0.1)
				(type default)
			)
			(layer "B.Fab")
		)
		(fp_line
			(start 0.12065 -0.305054)
			(end 0.12065 -0.2794)
			(stroke
				(width 0.1)
				(type default)
			)
			(layer "B.Fab")
		)
		(fp_line
			(start -0.120396 0.3048)
			(end -0.120396 0.2794)
			(stroke
				(width 0.1)
				(type default)
			)
			(layer "B.Fab")
		)
		(fp_line
			(start -0.120396 0.2794)
			(end 0.12065 0.2794)
			(stroke
				(width 0.1)
				(type default)
			)
			(layer "B.Fab")
		)
		(fp_line
			(start -0.12065 -0.2794)
			(end -0.12065 -0.3048)
			(stroke
				(width 0.1)
				(type default)
			)
			(layer "B.Fab")
		)
		(fp_line
			(start -0.12065 -0.3048)
			(end -0.67945 -0.3048)
			(stroke
				(width 0.1)
				(type default)
			)
			(layer "B.Fab")
		)
		(fp_line
			(start -0.67945 0.3048)
			(end -0.120396 0.3048)
			(stroke
				(width 0.1)
				(type default)
			)
			(layer "B.Fab")
		)
		(fp_line
			(start -0.67945 -0.3048)
			(end -0.67945 0.3048)
			(stroke
				(width 0.1)
				(type default)
			)
			(layer "B.Fab")
		)
		(pad "1" smd circle
			(at 0.40005 0)
			(size 0 0)
			(layers "B.Cu" "B.Mask" "B.Paste")
			(net "LED_POSTCODE_A0")
		)
		(pad "2" smd circle
			(at -0.40005 0)
			(size 0 0)
			(layers "B.Cu" "B.Mask" "B.Paste")
			(net "GND")
		)
	)
	(footprint ""
		(layer "B.Cu")
		(at 5.334 -81.534 -90)
		(property "Reference" "R10"
			(at 0 0 90)
			(layer "B.SilkS")
			(hide yes)
			(effects
				(font
					(size 1.27 1.27)
				)
				(justify mirror)
			)
		)
		(property "Value" ""
			(at 0 0 90)
			(layer "B.Fab")
			(effects
				(font
					(size 1.27 1.27)
				)
				(justify mirror)
			)
		)
		(duplicate_pad_numbers_are_jumpers no)
		(fp_line
			(start -0.7874 0.4064)
			(end 0.7874 0.4064)
			(stroke
				(width 0.1524)
				(type default)
			)
			(layer "B.SilkS")
		)
		(fp_line
			(start 0.7874 0.4064)
			(end 0.7874 -0.4064)
			(stroke
				(width 0.1524)
				(type default)
			)
			(layer "B.SilkS")
		)
		(fp_line
			(start -0.7874 -0.4064)
			(end -0.7874 0.4064)
			(stroke
				(width 0.1524)
				(type default)
			)
			(layer "B.SilkS")
		)
		(fp_line
			(start 0.7874 -0.4064)
			(end -0.7874 -0.4064)
			(stroke
				(width 0.1524)
				(type default)
			)
			(layer "B.SilkS")
		)
		(fp_line
			(start -0.67945 0.3048)
			(end -0.120396 0.3048)
			(stroke
				(width 0.1)
				(type default)
			)
			(layer "B.Fab")
		)
		(fp_line
			(start -0.120396 0.3048)
			(end -0.120396 0.2794)
			(stroke
				(width 0.1)
				(type default)
			)
			(layer "B.Fab")
		)
		(fp_line
			(start 0.12065 0.3048)
			(end 0.67945 0.3048)
			(stroke
				(width 0.1)
				(type default)
			)
			(layer "B.Fab")
		)
		(fp_line
			(start 0.67945 0.3048)
			(end 0.67945 -0.305054)
			(stroke
				(width 0.1)
				(type default)
			)
			(layer "B.Fab")
		)
		(fp_line
			(start -0.120396 0.2794)
			(end 0.12065 0.2794)
			(stroke
				(width 0.1)
				(type default)
			)
			(layer "B.Fab")
		)
		(fp_line
			(start 0.12065 0.2794)
			(end 0.12065 0.3048)
			(stroke
				(width 0.1)
				(type default)
			)
			(layer "B.Fab")
		)
		(fp_line
			(start -0.12065 -0.2794)
			(end -0.12065 -0.3048)
			(stroke
				(width 0.1)
				(type default)
			)
			(layer "B.Fab")
		)
		(fp_line
			(start 0.12065 -0.2794)
			(end -0.12065 -0.2794)
			(stroke
				(width 0.1)
				(type default)
			)
			(layer "B.Fab")
		)
		(fp_line
			(start -0.67945 -0.3048)
			(end -0.67945 0.3048)
			(stroke
				(width 0.1)
				(type default)
			)
			(layer "B.Fab")
		)
		(fp_line
			(start -0.12065 -0.3048)
			(end -0.67945 -0.3048)
			(stroke
				(width 0.1)
				(type default)
			)
			(layer "B.Fab")
		)
		(fp_line
			(start 0.12065 -0.305054)
			(end 0.12065 -0.2794)
			(stroke
				(width 0.1)
				(type default)
			)
			(layer "B.Fab")
		)
		(fp_line
			(start 0.67945 -0.305054)
			(end 0.12065 -0.305054)
			(stroke
				(width 0.1)
				(type default)
			)
			(layer "B.Fab")
		)
		(pad "1" smd circle
			(at 0.40005 0 90)
			(size 0 0)
			(layers "B.Cu" "B.Mask" "B.Paste")
			(net "RST_SRST_PLD_BMC_R2_N")
		)
		(pad "2" smd circle
			(at -0.40005 0 90)
			(size 0 0)
			(layers "B.Cu" "B.Mask" "B.Paste")
			(net "RST_SRST_PLD_BMC_R_N")
		)
	)
	(footprint ""
		(layer "B.Cu")
		(at 22.65934 -95.187008 90)
		(property "Reference" "C285"
			(at 0 0 90)
			(layer "B.SilkS")
			(hide yes)
			(effects
				(font
					(size 1.27 1.27)
				)
				(justify mirror)
			)
		)
		(property "Value" ""
			(at 0 0 90)
			(layer "B.Fab")
			(effects
				(font
					(size 1.27 1.27)
				)
				(justify mirror)
			)
		)
		(duplicate_pad_numbers_are_jumpers no)
		(fp_line
			(start 0.69215 -0.2921)
			(end -0.69215 -0.2921)
			(stroke
				(width 0.1524)
				(type default)
			)
			(layer "B.SilkS")
		)
		(fp_line
			(start -0.69215 -0.2921)
			(end -0.69215 0.2921)
			(stroke
				(width 0.1524)
				(type default)
			)
			(layer "B.SilkS")
		)
		(fp_line
			(start 0.69215 0.2921)
			(end 0.69215 -0.2921)
			(stroke
				(width 0.1524)
				(type default)
			)
			(layer "B.SilkS")
		)
		(fp_line
			(start -0.69215 0.2921)
			(end 0.69215 0.2921)
			(stroke
				(width 0.1524)
				(type default)
			)
			(layer "B.SilkS")
		)
		(fp_line
			(start 0.51435 -0.2794)
			(end -0.51435 -0.2794)
			(stroke
				(width 0.1)
				(type default)
			)
			(layer "B.Fab")
		)
		(fp_line
			(start -0.51435 -0.2794)
			(end -0.51435 0.2794)
			(stroke
				(width 0.1)
				(type default)
			)
			(layer "B.Fab")
		)
		(fp_line
			(start 0.51435 0.2794)
			(end 0.51435 -0.2794)
			(stroke
				(width 0.1)
				(type default)
			)
			(layer "B.Fab")
		)
		(fp_line
			(start -0.51435 0.2794)
			(end 0.51435 0.2794)
			(stroke
				(width 0.1)
				(type default)
			)
			(layer "B.Fab")
		)
		(pad "1" smd circle
			(at 0.40005 0 270)
			(size 0 0)
			(layers "B.Cu" "B.Mask" "B.Paste")
			(net "VCCIO2")
		)
		(pad "2" smd circle
			(at -0.40005 0 270)
			(size 0 0)
			(layers "B.Cu" "B.Mask" "B.Paste")
			(net "GND")
		)
		(zone
			(layer "B.Cu")
			(hatch none 0.5)
			(connect_pads
				(clearance 0)
			)
			(min_thickness 0.25)
			(keepout
				(tracks not_allowed)
				(vias allowed)
				(pads allowed)
				(copperpour not_allowed)
				(footprints allowed)
			)
			(placement
				(enabled no)
				(sheetname "")
			)
			(fill
				(thermal_gap 0.5)
				(thermal_bridge_width 0.5)
				(island_removal_mode 0)
			)
			(polygon
				(pts
					(xy 22.74697 -95.377508) (xy 22.805136 -95.286068) (xy 22.805136 -95.086678) (xy 22.74697 -94.996508)
					(xy 22.57171 -94.996508) (xy 22.51329 -95.086678) (xy 22.51329 -95.286068) (xy 22.571456 -95.377508)
				)
			)
		)
	)
	(footprint ""
		(layer "B.Cu")
		(at 12.319 -96.52)
		(property "Reference" "R432"
			(at 0 0 0)
			(layer "B.SilkS")
			(hide yes)
			(effects
				(font
					(size 1.27 1.27)
				)
				(justify mirror)
			)
		)
		(property "Value" ""
			(at 0 0 0)
			(layer "B.Fab")
			(effects
				(font
					(size 1.27 1.27)
				)
				(justify mirror)
			)
		)
		(duplicate_pad_numbers_are_jumpers no)
		(fp_line
			(start -0.7874 -0.4064)
			(end -0.7874 0.4064)
			(stroke
				(width 0.1524)
				(type default)
			)
			(layer "B.SilkS")
		)
		(fp_line
			(start -0.7874 0.4064)
			(end 0.7874 0.4064)
			(stroke
				(width 0.1524)
				(type default)
			)
			(layer "B.SilkS")
		)
		(fp_line
			(start 0.7874 -0.4064)
			(end -0.7874 -0.4064)
			(stroke
				(width 0.1524)
				(type default)
			)
			(layer "B.SilkS")
		)
		(fp_line
			(start 0.7874 0.4064)
			(end 0.7874 -0.4064)
			(stroke
				(width 0.1524)
				(type default)
			)
			(layer "B.SilkS")
		)
		(fp_line
			(start -0.67945 -0.3048)
			(end -0.67945 0.3048)
			(stroke
				(width 0.1)
				(type default)
			)
			(layer "B.Fab")
		)
		(fp_line
			(start -0.67945 0.3048)
			(end -0.120396 0.3048)
			(stroke
				(width 0.1)
				(type default)
			)
			(layer "B.Fab")
		)
		(fp_line
			(start -0.12065 -0.3048)
			(end -0.67945 -0.3048)
			(stroke
				(width 0.1)
				(type default)
			)
			(layer "B.Fab")
		)
		(fp_line
			(start -0.12065 -0.2794)
			(end -0.12065 -0.3048)
			(stroke
				(width 0.1)
				(type default)
			)
			(layer "B.Fab")
		)
		(fp_line
			(start -0.120396 0.2794)
			(end 0.12065 0.2794)
			(stroke
				(width 0.1)
				(type default)
			)
			(layer "B.Fab")
		)
		(fp_line
			(start -0.120396 0.3048)
			(end -0.120396 0.2794)
			(stroke
				(width 0.1)
				(type default)
			)
			(layer "B.Fab")
		)
		(fp_line
			(start 0.12065 -0.305054)
			(end 0.12065 -0.2794)
			(stroke
				(width 0.1)
				(type default)
			)
			(layer "B.Fab")
		)
		(fp_line
			(start 0.12065 -0.2794)
			(end -0.12065 -0.2794)
			(stroke
				(width 0.1)
				(type default)
			)
			(layer "B.Fab")
		)
		(fp_line
			(start 0.12065 0.2794)
			(end 0.12065 0.3048)
			(stroke
				(width 0.1)
				(type default)
			)
			(layer "B.Fab")
		)
		(fp_line
			(start 0.12065 0.3048)
			(end 0.67945 0.3048)
			(stroke
				(width 0.1)
				(type default)
			)
			(layer "B.Fab")
		)
		(fp_line
			(start 0.67945 -0.305054)
			(end 0.12065 -0.305054)
			(stroke
				(width 0.1)
				(type default)
			)
			(layer "B.Fab")
		)
		(fp_line
			(start 0.67945 0.3048)
			(end 0.67945 -0.305054)
			(stroke
				(width 0.1)
				(type default)
			)
			(layer "B.Fab")
		)
		(pad "1" smd circle
			(at 0.40005 0 180)
			(size 0 0)
			(layers "B.Cu" "B.Mask" "B.Paste")
			(net "FM_PWR_R_BTN")
		)
		(pad "2" smd circle
			(at -0.40005 0 180)
			(size 0 0)
			(layers "B.Cu" "B.Mask" "B.Paste")
			(net "FM_PWR_BTN")
		)
	)
	(footprint ""
		(layer "B.Cu")
		(at 83.16722 -47.602394)
		(property "Reference" "R350"
			(at 0 0 0)
			(layer "B.SilkS")
			(hide yes)
			(effects
				(font
					(size 1.27 1.27)
				)
				(justify mirror)
			)
		)
		(property "Value" ""
			(at 0 0 0)
			(layer "B.Fab")
			(effects
				(font
					(size 1.27 1.27)
				)
				(justify mirror)
			)
		)
		(duplicate_pad_numbers_are_jumpers no)
		(fp_line
			(start -0.7874 -0.4064)
			(end -0.7874 0.4064)
			(stroke
				(width 0.1524)
				(type default)
			)
			(layer "B.SilkS")
		)
		(fp_line
			(start -0.7874 0.4064)
			(end 0.7874 0.4064)
			(stroke
				(width 0.1524)
				(type default)
			)
			(layer "B.SilkS")
		)
		(fp_line
			(start 0.7874 -0.4064)
			(end -0.7874 -0.4064)
			(stroke
				(width 0.1524)
				(type default)
			)
			(layer "B.SilkS")
		)
		(fp_line
			(start 0.7874 0.4064)
			(end 0.7874 -0.4064)
			(stroke
				(width 0.1524)
				(type default)
			)
			(layer "B.SilkS")
		)
		(fp_line
			(start -0.67945 -0.3048)
			(end -0.67945 0.3048)
			(stroke
				(width 0.1)
				(type default)
			)
			(layer "B.Fab")
		)
		(fp_line
			(start -0.67945 0.3048)
			(end -0.120396 0.3048)
			(stroke
				(width 0.1)
				(type default)
			)
			(layer "B.Fab")
		)
		(fp_line
			(start -0.12065 -0.3048)
			(end -0.67945 -0.3048)
			(stroke
				(width 0.1)
				(type default)
			)
			(layer "B.Fab")
		)
		(fp_line
			(start -0.12065 -0.2794)
			(end -0.12065 -0.3048)
			(stroke
				(width 0.1)
				(type default)
			)
			(layer "B.Fab")
		)
		(fp_line
			(start -0.120396 0.2794)
			(end 0.12065 0.2794)
			(stroke
				(width 0.1)
				(type default)
			)
			(layer "B.Fab")
		)
		(fp_line
			(start -0.120396 0.3048)
			(end -0.120396 0.2794)
			(stroke
				(width 0.1)
				(type default)
			)
			(layer "B.Fab")
		)
		(fp_line
			(start 0.12065 -0.305054)
			(end 0.12065 -0.2794)
			(stroke
				(width 0.1)
				(type default)
			)
			(layer "B.Fab")
		)
		(fp_line
			(start 0.12065 -0.2794)
			(end -0.12065 -0.2794)
			(stroke
				(width 0.1)
				(type default)
			)
			(layer "B.Fab")
		)
		(fp_line
			(start 0.12065 0.2794)
			(end 0.12065 0.3048)
			(stroke
				(width 0.1)
				(type default)
			)
			(layer "B.Fab")
		)
		(fp_line
			(start 0.12065 0.3048)
			(end 0.67945 0.3048)
			(stroke
				(width 0.1)
				(type default)
			)
			(layer "B.Fab")
		)
		(fp_line
			(start 0.67945 -0.305054)
			(end 0.12065 -0.305054)
			(stroke
				(width 0.1)
				(type default)
			)
			(layer "B.Fab")
		)
		(fp_line
			(start 0.67945 0.3048)
			(end 0.67945 -0.305054)
			(stroke
				(width 0.1)
				(type default)
			)
			(layer "B.Fab")
		)
		(pad "1" smd circle
			(at 0.40005 0 180)
			(size 0 0)
			(layers "B.Cu" "B.Mask" "B.Paste")
			(net "GND")
		)
		(pad "2" smd circle
			(at -0.40005 0 180)
			(size 0 0)
			(layers "B.Cu" "B.Mask" "B.Paste")
			(net "M_BMC_DDR4_MBG1")
		)
	)
)
